# T6G (Grand Teton) — schematic netlist excerpt (pin names and nets, part order shuffled) for the footprints in the layout excerpt that follows; sources: Cadence DE-HDL packaged netlist, KiCad conversion of 04192023_DAF0TMB3IC0_F0TG_MB_C_brd_V02_OCP.brd

J28  SCONN288_DDR506112002KQ  IO  pkg DDR288S_1-1VXC  page 100
  VIN_BULK0  = P12V_MEM_CPU1
  RFU0  = NC
  VIN_MGMT  = P3V3_AUX
  HSCL  = I3C_SPD_DDRC_CPU1_SCL
  HSDA  = I3C_SPD_DDRC_CPU1_SDA
  VSS0  = GND
  DQ0_A  = M_C_CPU1_SA_DQ<0>
  VSS1  = GND
  DQ1_A  = M_C_CPU1_SA_DQ<1>
  VSS2  = GND
  DQS0_A_T  = M_C_CPU1_SA_DQS_DP<0>
  DQS0_A_C  = M_C_CPU1_SA_DQS_DN<0>
  VSS3  = GND
  DQ4_A  = M_C_CPU1_SA_DQ<4>
  VSS4  = GND
  DQ5_A  = M_C_CPU1_SA_DQ<5>
  VSS5  = GND
  DQ8_A  = M_C_CPU1_SA_DQ<8>
  VSS6  = GND
  DQ9_A  = M_C_CPU1_SA_DQ<9>
  VSS7  = GND
  DQS1_A_T  = M_C_CPU1_SA_DQS_DP<1>
  DQS1_A_C  = M_C_CPU1_SA_DQS_DN<1>
  VSS8  = GND
  DQ12_A  = M_C_CPU1_SA_DQ<12>
  VSS9  = GND
  DQ13_A  = M_C_CPU1_SA_DQ<13>
  VSS10  = GND
  DQ16_A  = M_C_CPU1_SA_DQ<16>
  VSS11  = GND
  DQ17_A  = M_C_CPU1_SA_DQ<17>
  VSS12  = GND
  DQS2_A_T  = M_C_CPU1_SA_DQS_DP<2>
  DQS2_A_C  = M_C_CPU1_SA_DQS_DN<2>
  VSS13  = GND
  DQ20_A  = M_C_CPU1_SA_DQ<20>
  VSS14  = GND
  DQ21_A  = M_C_CPU1_SA_DQ<21>
  VSS15  = GND
  DQ24_A  = M_C_CPU1_SA_DQ<24>
  VSS16  = GND
  DQ25_A  = M_C_CPU1_SA_DQ<25>
  VSS17  = GND
  DQS3_A_T  = M_C_CPU1_SA_DQS_DP<3>
  DQS3_A_C  = M_C_CPU1_SA_DQS_DN<3>
  VSS18  = GND
  DQ28_A  = M_C_CPU1_SA_DQ<28>
  VSS19  = GND
  DQ29_A  = M_C_CPU1_SA_DQ<29>
  VSS20  = GND
  CB0_A  = M_C_CPU1_SA_CB<0>
  VSS21  = GND
  CB1_A  = M_C_CPU1_SA_CB<1>
  VSS22  = GND
  DQS4_A_T  = M_C_CPU1_SA_DQS_DP<4>
  DQS4_A_C  = M_C_CPU1_SA_DQS_DN<4>
  VSS23  = GND
  CB4_A  = M_C_CPU1_SA_CB<4>
  VSS24  = GND
  CB5_A  = M_C_CPU1_SA_CB<5>
  VSS25  = GND
  ALERT_N  = M_C_CPU1_ALERT_N
  VSS26  = GND
  CS0_A_N  = M_C_CPU1_SA_CS_N<0>
  VSS27  = GND
  CA0_A  = M_C_CPU1_SA_CA<0>
  VSS28  = GND
  CA2_A  = M_C_CPU1_SA_CA<2>
  VSS29  = GND
  CA4_A  = M_C_CPU1_SA_CA<4>
  VSS30  = GND
  CA6_A  = M_C_CPU1_SA_CA<6>
  VSS31  = GND
  PAR_A  = M_C_CPU1_SA_PAR
  VSS32  = GND
  CA0_B  = M_C_CPU1_SB_CA<0>
  VSS33  = GND
  CA2_B  = M_C_CPU1_SB_CA<2>
  VSS34  = GND
  CA4_B  = M_C_CPU1_SB_CA<4>
  VSS35  = GND
  CA6_B  = M_C_CPU1_SB_CA<6>
  VSS36  = GND
  CS0_B_N  = M_C_CPU1_SB_CS_N<0>
  VSS37  = GND
  \lbd||rsp_a_n\  = M_C_CPU1_SA_RSP<0>
  \lbs||rsp_b_n\  = M_C_CPU1_SB_RSP<0>
  VSS38  = GND
  CB4_B  = M_C_CPU1_SB_CB<4>
  VSS39  = GND
  CB5_B  = M_C_CPU1_SB_CB<5>
  VSS40  = GND
  \dqs9_b_t||tdqs9_b_t||dbi4_b_n\  = M_C_CPU1_SB_DQS_DP<9>
  \dqs9_b_c||tdqs9_b_c\  = M_C_CPU1_SB_DQS_DN<9>
  VSS41  = GND
  CB0_B  = M_C_CPU1_SB_CB<0>
  VSS42  = GND
  CB1_B  = M_C_CPU1_SB_CB<1>
  VSS43  = GND
  DQ0_B  = M_C_CPU1_SB_DQ<0>
  VSS44  = GND
  DQ1_B  = M_C_CPU1_SB_DQ<1>
  VSS45  = GND
  DQS0_B_T  = M_C_CPU1_SB_DQS_DP<0>
  DQS0_B_C  = M_C_CPU1_SB_DQS_DN<0>
  VSS46  = GND
  DQ4_B  = M_C_CPU1_SB_DQ<4>
  VSS47  = GND
  DQ5_B  = M_C_CPU1_SB_DQ<5>
  VSS48  = GND
  DQ8_B  = M_C_CPU1_SB_DQ<8>
  VSS49  = GND
  DQ9_B  = M_C_CPU1_SB_DQ<9>
  VSS50  = GND
  DQS1_B_T  = M_C_CPU1_SB_DQS_DP<1>
  DQS1_B_C  = M_C_CPU1_SB_DQS_DN<1>
  VSS51  = GND
  DQ12_B  = M_C_CPU1_SB_DQ<12>
  VSS52  = GND
  DQ13_B  = M_C_CPU1_SB_DQ<13>
  VSS53  = GND
  DQ16_B  = M_C_CPU1_SB_DQ<16>
  VSS54  = GND
  DQ17_B  = M_C_CPU1_SB_DQ<17>
  VSS55  = GND
  DQS2_B_T  = M_C_CPU1_SB_DQS_DP<2>
  DQS2_B_C  = M_C_CPU1_SB_DQS_DN<2>
  VSS56  = GND
  DQ20_B  = M_C_CPU1_SB_DQ<20>
  VSS57  = GND
  DQ21_B  = M_C_CPU1_SB_DQ<21>
  VSS58  = GND
  DQ24_B  = M_C_CPU1_SB_DQ<24>
  VSS59  = GND
  DQ25_B  = M_C_CPU1_SB_DQ<25>
  VSS60  = GND
  DQS3_B_T  = M_C_CPU1_SB_DQS_DP<3>
  DQS3_B_C  = M_C_CPU1_SB_DQS_DN<3>
  VSS61  = GND
  DQ28_B  = M_C_CPU1_SB_DQ<28>
  VSS62  = GND
  DQ29_B  = M_C_CPU1_SB_DQ<29>
  VSS63  = GND
  RFU1  = NC
  VIN_BULK1  = P12V_MEM_CPU1
  VIN_BULK2  = P12V_MEM_CPU1
  \pwr_good||fail_n\  = PWRGD_CHC_CPU1_DIMM
  HAS  = PD_CHC_CPU1_DIMM_SAA
  RFU2  = NC
  RFU3  = NC
  VSS64  = GND
  DQ2_A  = M_C_CPU1_SA_DQ<2>
  VSS65  = GND
  DQ3_A  = M_C_CPU1_SA_DQ<3>
  VSS66  = GND
  \dqs5_a_c||tdqs5_a_c||dqs5_a_t||tdqs5_a_t\  = M_C_CPU1_SA_DQS_DN<5>
  \dqs5_a_t||tdqs5_a_t\  = M_C_CPU1_SA_DQS_DP<5>
  VSS67  = GND
  DQ6_A  = M_C_CPU1_SA_DQ<6>
  VSS68  = GND
  DQ7_A  = M_C_CPU1_SA_DQ<7>
  VSS69  = GND
  DQ10_A  = M_C_CPU1_SA_DQ<10>
  VSS70  = GND
  DQ11_A  = M_C_CPU1_SA_DQ<11>
  VSS71  = GND
  \dqs6_a_c||tdqs6_a_c||dqs6_a_t||tdqs6_a_t\  = M_C_CPU1_SA_DQS_DN<6>
  \dqs6_a_t||tdqs6_a_t\  = M_C_CPU1_SA_DQS_DP<6>
  VSS72  = GND
  DQ14_A  = M_C_CPU1_SA_DQ<14>
  VSS73  = GND
  DQ15_A  = M_C_CPU1_SA_DQ<15>
  VSS74  = GND
  DQ18_A  = M_C_CPU1_SA_DQ<18>
  VSS75  = GND
  DQ19_A  = M_C_CPU1_SA_DQ<19>
  VSS76  = GND
  \dqs7_a_c||tdqs7_a_c\  = M_C_CPU1_SA_DQS_DN<7>
  \dqs7_a_t||tdqs7_a_t\  = M_C_CPU1_SA_DQS_DP<7>
  VSS77  = GND
  DQ22_A  = M_C_CPU1_SA_DQ<22>
  VSS78  = GND
  DQ23_A  = M_C_CPU1_SA_DQ<23>
  VSS79  = GND
  DQ26_A  = M_C_CPU1_SA_DQ<26>
  VSS80  = GND
  DQ27_A  = M_C_CPU1_SA_DQ<27>
  VSS81  = GND
  \dqs8_a_c||tdqs8_a_c\  = M_C_CPU1_SA_DQS_DN<8>
  \dqs8_a_t||tdqs8_a_t\  = M_C_CPU1_SA_DQS_DP<8>
  VSS82  = GND
  DQ30_A  = M_C_CPU1_SA_DQ<30>
  VSS83  = GND
  DQ31_A  = M_C_CPU1_SA_DQ<31>
  VSS84  = GND
  CB2_A  = M_C_CPU1_SA_CB<2>
  VSS85  = GND
  CB3_A  = M_C_CPU1_SA_CB<3>
  VSS86  = GND
  \dqs9_a_c||tdqs9_a_c\  = M_C_CPU1_SA_DQS_DN<9>
  \dqs9_a_t||tdqs9_a_t\  = M_C_CPU1_SA_DQS_DP<9>
  VSS87  = GND
  CB6_A  = M_C_CPU1_SA_CB<6>
  VSS88  = GND
  CB7_A  = M_C_CPU1_SA_CB<7>
  VSS89  = GND
  RESET_N  = M_C_CPU1_RESET_N
  VSS90  = GND
  CS1_A_N  = M_C_CPU1_SA_CS_N<1>
  VSS91  = GND
  CA1_A  = M_C_CPU1_SA_CA<1>
  VSS92  = GND
  CA3_A  = M_C_CPU1_SA_CA<3>
  VSS93  = GND
  CA5_A  = M_C_CPU1_SA_CA<5>
  VSS94  = GND
  CK_T  = M_C_CPU1_CLK_DP<0>
  CK_C  = M_C_CPU1_CLK_DN<0>
  VSS95  = GND
  RFU4  = NC
  CA1_B  = M_C_CPU1_SB_CA<1>
  VSS96  = GND
  CA3_B  = M_C_CPU1_SB_CA<3>
  VSS97  = GND
  CA5_B  = M_C_CPU1_SB_CA<5>
  VSS98  = GND
  PAR_B  = M_C_CPU1_SB_PAR
  VSS99  = GND
  CS1_B_N  = M_C_CPU1_SB_CS_N<1>
  VSS100  = GND
  RFU5  = NC
  RFU6  = NC
  VSS101  = GND
  CB6_B  = M_C_CPU1_SB_CB<6>
  VSS102  = GND
  CB7_B  = M_C_CPU1_SB_CB<7>
  VSS103  = GND
  DQS4_B_C  = M_C_CPU1_SB_DQS_DN<4>
  DQS4_B_T  = M_C_CPU1_SB_DQS_DP<4>
  VSS104  = GND
  CB2_B  = M_C_CPU1_SB_CB<2>
  VSS105  = GND
  CB3_B  = M_C_CPU1_SB_CB<3>
  VSS106  = GND
  DQ2_B  = M_C_CPU1_SB_DQ<2>
  VSS107  = GND
  DQ3_B  = M_C_CPU1_SB_DQ<3>
  VSS108  = GND
  \dqs5_b_c||tdqs5_b_c\  = M_C_CPU1_SB_DQS_DN<5>
  \dqs5_b_t||tdqs5_b_t\  = M_C_CPU1_SB_DQS_DP<5>
  VSS109  = GND
  DQ6_B  = M_C_CPU1_SB_DQ<6>
  VSS110  = GND
  DQ7_B  = M_C_CPU1_SB_DQ<7>
  VSS111  = GND
  DQ10_B  = M_C_CPU1_SB_DQ<10>
  VSS112  = GND
  DQ11_B  = M_C_CPU1_SB_DQ<11>
  VSS113  = GND
  \dqs6_b_c||tdqs6_b_c\  = M_C_CPU1_SB_DQS_DN<6>
  \dqs6_b_t||tdqs6_b_t\  = M_C_CPU1_SB_DQS_DP<6>
  VSS114  = GND
  DQ14_B  = M_C_CPU1_SB_DQ<14>
  VSS115  = GND
  DQ15_B  = M_C_CPU1_SB_DQ<15>
  VSS116  = GND
  DQ18_B  = M_C_CPU1_SB_DQ<18>
  VSS117  = GND
  DQ19_B  = M_C_CPU1_SB_DQ<19>
  VSS118  = GND
  \dqs7_b_c||tdqs7_b_c\  = M_C_CPU1_SB_DQS_DN<7>
  \dqs7_b_t||tdqs7_b_t\  = M_C_CPU1_SB_DQS_DP<7>
  VSS119  = GND
  DQ22_B  = M_C_CPU1_SB_DQ<22>
  VSS120  = GND
  DQ23_B  = M_C_CPU1_SB_DQ<23>
  VSS121  = GND
  DQ26_B  = M_C_CPU1_SB_DQ<26>
  VSS122  = GND
  DQ27_B  = M_C_CPU1_SB_DQ<27>
  VSS123  = GND
  \dqs8_b_c||tdqs8_b_c\  = M_C_CPU1_SB_DQS_DN<8>
  \dqs8_b_t||tdqs8_b_t\  = M_C_CPU1_SB_DQS_DP<8>
  VSS124  = GND
  DQ30_B  = M_C_CPU1_SB_DQ<30>
  VSS125  = GND
  DQ31_B  = M_C_CPU1_SB_DQ<31>
  VSS126  = GND
  G1  = GND
  G2  = GND
  G3  = GND

(kicad_pcb
	(version 20260206)
	(generator "pcbnew")
	(generator_version "10.0")
	(general
		(thickness 1.6)
		(legacy_teardrops no)
	)
	(paper "A4")
	(title_block
		(title "04192023_DAF0TMB3IC0_F0TG_MB_C_brd_V02_OCP.brd")
		(comment 1 "Grand Teton / footprint 4188 of 8354 (J28), pads 47-92 of 291")
	)
	(layers
		(0 "F.Cu" signal "TOP")
		(4 "In1.Cu" signal "GND")
		(6 "In2.Cu" signal "IN1")
		(8 "In3.Cu" signal "GND1")
		(10 "In4.Cu" signal "IN2")
		(12 "In5.Cu" signal "GND2")
		(14 "In6.Cu" signal "IN3")
		(16 "In7.Cu" signal "GND3")
		(18 "In8.Cu" signal "VCC")
		(20 "In9.Cu" signal "VCC1")
		(22 "In10.Cu" signal "GND4")
		(24 "In11.Cu" signal "IN4")
		(26 "In12.Cu" signal "GND5")
		(28 "In13.Cu" signal "IN5")
		(30 "In14.Cu" signal "GND6")
		(32 "In15.Cu" signal "IN6")
		(34 "In16.Cu" signal "GND7")
		(2 "B.Cu" signal "BOTTOM")
		(9 "F.Adhes" user "F.Adhesive")
		(11 "B.Adhes" user "B.Adhesive")
		(13 "F.Paste" user "Package Geometry/Pastemask Top")
		(15 "B.Paste" user "Package Geometry/Pastemask Bottom")
		(5 "F.SilkS" user "Ref Des/Silkscreen Top")
		(7 "B.SilkS" user "Ref Des/Silkscreen Bottom")
		(1 "F.Mask" user "Board Geometry/Soldermask Top")
		(3 "B.Mask" user "Board Geometry/Soldermask Bottom")
		(17 "Dwgs.User" user "User.Drawings")
		(19 "Cmts.User" user "User.Comments")
		(21 "Eco1.User" user "User.Eco1")
		(23 "Eco2.User" user "User.Eco2")
		(25 "Edge.Cuts" user "Board Geometry/Outline")
		(27 "Margin" user)
		(31 "F.CrtYd" user "Package Geometry/Place Bound Top")
		(29 "B.CrtYd" user "Package Geometry/Place Bound Bottom")
		(35 "F.Fab" user "Ref Des/Assembly Top")
		(33 "B.Fab" user "Ref Des/Assembly Bottom")
	)
	(footprint ""
		(layer "F.Cu")
		(at 42.289984 -255.560322 180)
		(property "Reference" "J28"
			(at -2.876296 -82.230976 0)
			(unlocked yes)
			(layer "F.SilkS")
			(effects
				(font
					(size 0.7874 0.5842)
					(thickness 0.1524)
				)
			)
		)
		(property "Value" ""
			(at 0 0 180)
			(layer "F.Fab")
			(effects
				(font
					(size 1.27 1.27)
				)
			)
		)
		(duplicate_pad_numbers_are_jumpers no)
		(pad "47" smd rect
			(at -2.050034 -24.224996 90)
			(size 0.519938 1.4986)
			(layers "F.Cu" "F.Mask" "F.Paste")
			(net "M_C_CPU1_SA_DQ<28>")
		)
		(pad "48" smd rect
			(at -2.050034 -23.375112 90)
			(size 0.519938 1.4986)
			(layers "F.Cu" "F.Mask" "F.Paste")
			(net "GND")
		)
		(pad "49" smd rect
			(at -2.050034 -22.524974 90)
			(size 0.519938 1.4986)
			(layers "F.Cu" "F.Mask" "F.Paste")
			(net "M_C_CPU1_SA_DQ<29>")
		)
		(pad "50" smd rect
			(at -2.050034 -21.67509 90)
			(size 0.519938 1.4986)
			(layers "F.Cu" "F.Mask" "F.Paste")
			(net "GND")
		)
		(pad "51" smd rect
			(at -2.050034 -20.824952 90)
			(size 0.519938 1.4986)
			(layers "F.Cu" "F.Mask" "F.Paste")
			(net "M_C_CPU1_SA_CB<0>")
		)
		(pad "52" smd rect
			(at -2.050034 -19.975068 90)
			(size 0.519938 1.4986)
			(layers "F.Cu" "F.Mask" "F.Paste")
			(net "GND")
		)
		(pad "53" smd rect
			(at -2.050034 -19.12493 90)
			(size 0.519938 1.4986)
			(layers "F.Cu" "F.Mask" "F.Paste")
			(net "M_C_CPU1_SA_CB<1>")
		)
		(pad "54" smd rect
			(at -2.050034 -18.275046 90)
			(size 0.519938 1.4986)
			(layers "F.Cu" "F.Mask" "F.Paste")
			(net "GND")
		)
		(pad "55" smd rect
			(at -2.050034 -17.424908 90)
			(size 0.519938 1.4986)
			(layers "F.Cu" "F.Mask" "F.Paste")
			(net "M_C_CPU1_SA_DQS_DP<4>")
		)
		(pad "56" smd rect
			(at -2.050034 -16.575024 90)
			(size 0.519938 1.4986)
			(layers "F.Cu" "F.Mask" "F.Paste")
			(net "M_C_CPU1_SA_DQS_DN<4>")
		)
		(pad "57" smd rect
			(at -2.050034 -15.724886 90)
			(size 0.519938 1.4986)
			(layers "F.Cu" "F.Mask" "F.Paste")
			(net "GND")
		)
		(pad "58" smd rect
			(at -2.050034 -14.875002 90)
			(size 0.519938 1.4986)
			(layers "F.Cu" "F.Mask" "F.Paste")
			(net "M_C_CPU1_SA_CB<4>")
		)
		(pad "59" smd rect
			(at -2.050034 -14.025118 90)
			(size 0.519938 1.4986)
			(layers "F.Cu" "F.Mask" "F.Paste")
			(net "GND")
		)
		(pad "60" smd rect
			(at -2.050034 -13.17498 90)
			(size 0.519938 1.4986)
			(layers "F.Cu" "F.Mask" "F.Paste")
			(net "M_C_CPU1_SA_CB<5>")
		)
		(pad "61" smd rect
			(at -2.050034 -12.325096 90)
			(size 0.519938 1.4986)
			(layers "F.Cu" "F.Mask" "F.Paste")
			(net "GND")
		)
		(pad "62" smd rect
			(at -2.050034 -11.474958 90)
			(size 0.519938 1.4986)
			(layers "F.Cu" "F.Mask" "F.Paste")
			(net "M_C_CPU1_ALERT_N")
		)
		(pad "63" smd rect
			(at -2.050034 -10.625074 90)
			(size 0.519938 1.4986)
			(layers "F.Cu" "F.Mask" "F.Paste")
			(net "GND")
		)
		(pad "64" smd rect
			(at -2.050034 -9.774936 90)
			(size 0.519938 1.4986)
			(layers "F.Cu" "F.Mask" "F.Paste")
			(net "M_C_CPU1_SA_CS_N<0>")
		)
		(pad "65" smd rect
			(at -2.050034 -8.925052 90)
			(size 0.519938 1.4986)
			(layers "F.Cu" "F.Mask" "F.Paste")
			(net "GND")
		)
		(pad "66" smd rect
			(at -2.050034 -8.074914 90)
			(size 0.519938 1.4986)
			(layers "F.Cu" "F.Mask" "F.Paste")
			(net "M_C_CPU1_SA_CA<0>")
		)
		(pad "67" smd rect
			(at -2.050034 -7.22503 90)
			(size 0.519938 1.4986)
			(layers "F.Cu" "F.Mask" "F.Paste")
			(net "GND")
		)
		(pad "68" smd rect
			(at -2.050034 -6.374892 90)
			(size 0.519938 1.4986)
			(layers "F.Cu" "F.Mask" "F.Paste")
			(net "M_C_CPU1_SA_CA<2>")
		)
		(pad "69" smd rect
			(at -2.050034 -5.525008 90)
			(size 0.519938 1.4986)
			(layers "F.Cu" "F.Mask" "F.Paste")
			(net "GND")
		)
		(pad "70" smd rect
			(at -2.050034 -4.675124 90)
			(size 0.519938 1.4986)
			(layers "F.Cu" "F.Mask" "F.Paste")
			(net "M_C_CPU1_SA_CA<4>")
		)
		(pad "71" smd rect
			(at -2.050034 -3.824986 90)
			(size 0.519938 1.4986)
			(layers "F.Cu" "F.Mask" "F.Paste")
			(net "GND")
		)
		(pad "72" smd rect
			(at -2.050034 -2.975102 90)
			(size 0.519938 1.4986)
			(layers "F.Cu" "F.Mask" "F.Paste")
			(net "M_C_CPU1_SA_CA<6>")
		)
		(pad "73" smd rect
			(at -2.050034 -2.124964 90)
			(size 0.519938 1.4986)
			(layers "F.Cu" "F.Mask" "F.Paste")
			(net "GND")
		)
		(pad "74" smd rect
			(at -2.050034 -1.27508 90)
			(size 0.519938 1.4986)
			(layers "F.Cu" "F.Mask" "F.Paste")
			(net "M_C_CPU1_SA_PAR")
		)
		(pad "75" smd rect
			(at -2.050034 -0.424942 90)
			(size 0.519938 1.4986)
			(layers "F.Cu" "F.Mask" "F.Paste")
			(net "GND")
		)
		(pad "76" smd rect
			(at -2.050034 5.525008 90)
			(size 0.519938 1.4986)
			(layers "F.Cu" "F.Mask" "F.Paste")
			(net "M_C_CPU1_SB_CA<0>")
		)
		(pad "77" smd rect
			(at -2.050034 6.374892 90)
			(size 0.519938 1.4986)
			(layers "F.Cu" "F.Mask" "F.Paste")
			(net "GND")
		)
		(pad "78" smd rect
			(at -2.050034 7.22503 90)
			(size 0.519938 1.4986)
			(layers "F.Cu" "F.Mask" "F.Paste")
			(net "M_C_CPU1_SB_CA<2>")
		)
		(pad "79" smd rect
			(at -2.050034 8.074914 90)
			(size 0.519938 1.4986)
			(layers "F.Cu" "F.Mask" "F.Paste")
			(net "GND")
		)
		(pad "80" smd rect
			(at -2.050034 8.925052 90)
			(size 0.519938 1.4986)
			(layers "F.Cu" "F.Mask" "F.Paste")
			(net "M_C_CPU1_SB_CA<4>")
		)
		(pad "81" smd rect
			(at -2.050034 9.774936 90)
			(size 0.519938 1.4986)
			(layers "F.Cu" "F.Mask" "F.Paste")
			(net "GND")
		)
		(pad "82" smd rect
			(at -2.050034 10.625074 90)
			(size 0.519938 1.4986)
			(layers "F.Cu" "F.Mask" "F.Paste")
			(net "M_C_CPU1_SB_CA<6>")
		)
		(pad "83" smd rect
			(at -2.050034 11.474958 90)
			(size 0.519938 1.4986)
			(layers "F.Cu" "F.Mask" "F.Paste")
			(net "GND")
		)
		(pad "84" smd rect
			(at -2.050034 12.325096 90)
			(size 0.519938 1.4986)
			(layers "F.Cu" "F.Mask" "F.Paste")
			(net "M_C_CPU1_SB_CS_N<0>")
		)
		(pad "85" smd rect
			(at -2.050034 13.17498 90)
			(size 0.519938 1.4986)
			(layers "F.Cu" "F.Mask" "F.Paste")
			(net "GND")
		)
		(pad "86" smd rect
			(at -2.050034 14.025118 90)
			(size 0.519938 1.4986)
			(layers "F.Cu" "F.Mask" "F.Paste")
			(net "M_C_CPU1_SA_RSP<0>")
		)
		(pad "87" smd rect
			(at -2.050034 14.875002 90)
			(size 0.519938 1.4986)
			(layers "F.Cu" "F.Mask" "F.Paste")
			(net "M_C_CPU1_SB_RSP<0>")
		)
		(pad "88" smd rect
			(at -2.050034 15.724886 90)
			(size 0.519938 1.4986)
			(layers "F.Cu" "F.Mask" "F.Paste")
			(net "GND")
		)
		(pad "89" smd rect
			(at -2.050034 16.575024 90)
			(size 0.519938 1.4986)
			(layers "F.Cu" "F.Mask" "F.Paste")
			(net "M_C_CPU1_SB_CB<4>")
		)
		(pad "90" smd rect
			(at -2.050034 17.424908 90)
			(size 0.519938 1.4986)
			(layers "F.Cu" "F.Mask" "F.Paste")
			(net "GND")
		)
		(pad "91" smd rect
			(at -2.050034 18.275046 90)
			(size 0.519938 1.4986)
			(layers "F.Cu" "F.Mask" "F.Paste")
			(net "M_C_CPU1_SB_CB<5>")
		)
		(pad "92" smd rect
			(at -2.050034 19.12493 90)
			(size 0.519938 1.4986)
			(layers "F.Cu" "F.Mask" "F.Paste")
			(net "GND")
		)
	)
)
